(kicad_pcb
	(version 20260206)
	(generator "pcbnew")
	(generator_version "10.0")
	(general
		(thickness 1.6)
		(legacy_teardrops no)
	)
	(paper "A4")
	(title_block
		(title "03242023_DA0F0TMBIJ0_F0T_Motherboard_J_brd_V01_OCP.brd")
		(comment 1 "Grand Teton / footprints 1035-1041 of 6105")
	)
	(layers
		(0 "F.Cu" signal "TOP")
		(4 "In1.Cu" signal "GND")
		(6 "In2.Cu" signal "IN1")
		(8 "In3.Cu" signal "GND1")
		(10 "In4.Cu" signal "IN2")
		(12 "In5.Cu" signal "GND2")
		(14 "In6.Cu" signal "IN3")
		(16 "In7.Cu" signal "GND3")
		(18 "In8.Cu" signal "VCC")
		(20 "In9.Cu" signal "VCC1")
		(22 "In10.Cu" signal "GND4")
		(24 "In11.Cu" signal "IN4")
		(26 "In12.Cu" signal "GND5")
		(28 "In13.Cu" signal "IN5")
		(30 "In14.Cu" signal "GND6")
		(32 "In15.Cu" signal "IN6")
		(34 "In16.Cu" signal "GND7")
		(2 "B.Cu" signal "BOTTOM")
		(9 "F.Adhes" user "F.Adhesive")
		(11 "B.Adhes" user "B.Adhesive")
		(13 "F.Paste" user "Package Geometry/Pastemask Top")
		(15 "B.Paste" user "Package Geometry/Pastemask Bottom")
		(5 "F.SilkS" user "Ref Des/Silkscreen Top")
		(7 "B.SilkS" user "Ref Des/Silkscreen Bottom")
		(1 "F.Mask" user "Board Geometry/Soldermask Top")
		(3 "B.Mask" user "Board Geometry/Soldermask Bottom")
		(17 "Dwgs.User" user "User.Drawings")
		(19 "Cmts.User" user "User.Comments")
		(21 "Eco1.User" user "User.Eco1")
		(23 "Eco2.User" user "User.Eco2")
		(25 "Edge.Cuts" user "Board Geometry/Outline")
		(27 "Margin" user)
		(31 "F.CrtYd" user "Package Geometry/Place Bound Top")
		(29 "B.CrtYd" user "Package Geometry/Place Bound Bottom")
		(35 "F.Fab" user "Ref Des/Assembly Top")
		(33 "B.Fab" user "Ref Des/Assembly Bottom")
	)
	(footprint ""
		(layer "F.Cu")
		(at 136.3853 -114.38382)
		(property "Reference" "R4754"
			(at 0 0 0)
			(layer "F.SilkS")
			(hide yes)
			(effects
				(font
					(size 1.27 1.27)
				)
			)
		)
		(property "Value" ""
			(at 0 0 0)
			(layer "F.Fab")
			(effects
				(font
					(size 1.27 1.27)
				)
			)
		)
		(duplicate_pad_numbers_are_jumpers no)
		(fp_line
			(start -0.7874 -0.4064)
			(end 0.7874 -0.4064)
			(stroke
				(width 0.1524)
				(type default)
			)
			(layer "F.SilkS")
		)
		(fp_line
			(start -0.7874 0.4064)
			(end -0.7874 -0.4064)
			(stroke
				(width 0.1524)
				(type default)
			)
			(layer "F.SilkS")
		)
		(fp_line
			(start 0.7874 -0.4064)
			(end 0.7874 0.4064)
			(stroke
				(width 0.1524)
				(type default)
			)
			(layer "F.SilkS")
		)
		(fp_line
			(start 0.7874 0.4064)
			(end -0.7874 0.4064)
			(stroke
				(width 0.1524)
				(type default)
			)
			(layer "F.SilkS")
		)
		(fp_line
			(start -0.67945 -0.305054)
			(end -0.12065 -0.305054)
			(stroke
				(width 0.1)
				(type default)
			)
			(layer "F.Fab")
		)
		(fp_line
			(start -0.67945 0.3048)
			(end -0.67945 -0.305054)
			(stroke
				(width 0.1)
				(type default)
			)
			(layer "F.Fab")
		)
		(fp_line
			(start -0.12065 -0.305054)
			(end -0.12065 -0.2794)
			(stroke
				(width 0.1)
				(type default)
			)
			(layer "F.Fab")
		)
		(fp_line
			(start -0.12065 -0.2794)
			(end 0.12065 -0.2794)
			(stroke
				(width 0.1)
				(type default)
			)
			(layer "F.Fab")
		)
		(fp_line
			(start -0.12065 0.2794)
			(end -0.12065 0.3048)
			(stroke
				(width 0.1)
				(type default)
			)
			(layer "F.Fab")
		)
		(fp_line
			(start -0.12065 0.3048)
			(end -0.67945 0.3048)
			(stroke
				(width 0.1)
				(type default)
			)
			(layer "F.Fab")
		)
		(fp_line
			(start 0.120396 0.2794)
			(end -0.12065 0.2794)
			(stroke
				(width 0.1)
				(type default)
			)
			(layer "F.Fab")
		)
		(fp_line
			(start 0.120396 0.3048)
			(end 0.120396 0.2794)
			(stroke
				(width 0.1)
				(type default)
			)
			(layer "F.Fab")
		)
		(fp_line
			(start 0.12065 -0.3048)
			(end 0.67945 -0.3048)
			(stroke
				(width 0.1)
				(type default)
			)
			(layer "F.Fab")
		)
		(fp_line
			(start 0.12065 -0.2794)
			(end 0.12065 -0.3048)
			(stroke
				(width 0.1)
				(type default)
			)
			(layer "F.Fab")
		)
		(fp_line
			(start 0.67945 -0.3048)
			(end 0.67945 0.3048)
			(stroke
				(width 0.1)
				(type default)
			)
			(layer "F.Fab")
		)
		(fp_line
			(start 0.67945 0.3048)
			(end 0.120396 0.3048)
			(stroke
				(width 0.1)
				(type default)
			)
			(layer "F.Fab")
		)
		(pad "1" smd circle
			(at -0.40005 0)
			(size 0 0)
			(layers "F.Cu" "F.Mask" "F.Paste")
			(net "HP_LVC3_OCP_V3_2_PWRGD_R")
		)
		(pad "2" smd circle
			(at 0.40005 0)
			(size 0 0)
			(layers "F.Cu" "F.Mask" "F.Paste")
			(net "HP_LVC3_OCP_V3_2_PWRGD_R2")
		)
	)
	(footprint ""
		(layer "F.Cu")
		(at 80.46847 -38.693852 180)
		(property "Reference" "U216"
			(at 1.35636 -2.19202 0)
			(unlocked yes)
			(layer "F.SilkS")
			(effects
				(font
					(size 0.7874 0.5842)
					(thickness 0.1524)
				)
				(justify left)
			)
		)
		(property "Value" ""
			(at 0 0 180)
			(layer "F.Fab")
			(effects
				(font
					(size 1.27 1.27)
				)
			)
		)
		(duplicate_pad_numbers_are_jumpers no)
		(fp_line
			(start 1.759712 1.500124)
			(end -1.759712 1.500124)
			(stroke
				(width 0.1524)
				(type default)
			)
			(layer "F.SilkS")
		)
		(fp_line
			(start 1.759712 -1.500124)
			(end 1.759712 1.500124)
			(stroke
				(width 0.1524)
				(type default)
			)
			(layer "F.SilkS")
		)
		(fp_line
			(start -1.759712 1.500124)
			(end -1.759712 -1.500124)
			(stroke
				(width 0.1524)
				(type default)
			)
			(layer "F.SilkS")
		)
		(fp_line
			(start -1.759712 -1.500124)
			(end 1.759712 -1.500124)
			(stroke
				(width 0.1524)
				(type default)
			)
			(layer "F.SilkS")
		)
		(fp_line
			(start 0.700024 1.500124)
			(end -0.700024 1.500124)
			(stroke
				(width 0.1)
				(type default)
			)
			(layer "F.Fab")
		)
		(fp_line
			(start 0.700024 -1.500124)
			(end 0.700024 1.500124)
			(stroke
				(width 0.1)
				(type default)
			)
			(layer "F.Fab")
		)
		(fp_line
			(start -0.700024 1.500124)
			(end -0.700024 -1.500124)
			(stroke
				(width 0.1)
				(type default)
			)
			(layer "F.Fab")
		)
		(fp_line
			(start -0.700024 -1.500124)
			(end 0.700024 -1.500124)
			(stroke
				(width 0.1)
				(type default)
			)
			(layer "F.Fab")
		)
		(pad "1" smd rect
			(at -1.150112 -0.94996 90)
			(size 0.6604 0.9652)
			(layers "F.Cu" "F.Mask" "F.Paste")
			(net "GND")
		)
		(pad "2" smd rect
			(at -1.150112 0.94996 90)
			(size 0.6604 0.9652)
			(layers "F.Cu" "F.Mask" "F.Paste")
			(net "HP_OCP_V3_2_RST")
		)
		(pad "3" smd rect
			(at 1.150112 0 90)
			(size 0.6604 0.9652)
			(layers "F.Cu" "F.Mask" "F.Paste")
			(net "P3V3_OCP_V3_2")
		)
	)
	(footprint ""
		(layer "F.Cu")
		(at 333.155544 -18.797524 -90)
		(property "Reference" "C606"
			(at 0 0 270)
			(layer "F.SilkS")
			(hide yes)
			(effects
				(font
					(size 1.27 1.27)
				)
			)
		)
		(property "Value" ""
			(at 0 0 270)
			(layer "F.Fab")
			(effects
				(font
					(size 1.27 1.27)
				)
			)
		)
		(duplicate_pad_numbers_are_jumpers no)
		(fp_line
			(start -0.7874 0.4064)
			(end -0.7874 -0.4064)
			(stroke
				(width 0.1524)
				(type default)
			)
			(layer "F.SilkS")
		)
		(fp_line
			(start 0.7874 0.4064)
			(end -0.7874 0.4064)
			(stroke
				(width 0.1524)
				(type default)
			)
			(layer "F.SilkS")
		)
		(fp_line
			(start -0.7874 -0.4064)
			(end 0.7874 -0.4064)
			(stroke
				(width 0.1524)
				(type default)
			)
			(layer "F.SilkS")
		)
		(fp_line
			(start 0.7874 -0.4064)
			(end 0.7874 0.4064)
			(stroke
				(width 0.1524)
				(type default)
			)
			(layer "F.SilkS")
		)
		(fp_line
			(start -0.67945 0.3048)
			(end -0.67945 -0.305054)
			(stroke
				(width 0.1)
				(type default)
			)
			(layer "F.Fab")
		)
		(fp_line
			(start -0.12065 0.3048)
			(end -0.67945 0.3048)
			(stroke
				(width 0.1)
				(type default)
			)
			(layer "F.Fab")
		)
		(fp_line
			(start 0.120396 0.3048)
			(end 0.120396 0.2794)
			(stroke
				(width 0.1)
				(type default)
			)
			(layer "F.Fab")
		)
		(fp_line
			(start 0.67945 0.3048)
			(end 0.120396 0.3048)
			(stroke
				(width 0.1)
				(type default)
			)
			(layer "F.Fab")
		)
		(fp_line
			(start -0.12065 0.2794)
			(end -0.12065 0.3048)
			(stroke
				(width 0.1)
				(type default)
			)
			(layer "F.Fab")
		)
		(fp_line
			(start 0.120396 0.2794)
			(end -0.12065 0.2794)
			(stroke
				(width 0.1)
				(type default)
			)
			(layer "F.Fab")
		)
		(fp_line
			(start -0.12065 -0.2794)
			(end 0.12065 -0.2794)
			(stroke
				(width 0.1)
				(type default)
			)
			(layer "F.Fab")
		)
		(fp_line
			(start 0.12065 -0.2794)
			(end 0.12065 -0.3048)
			(stroke
				(width 0.1)
				(type default)
			)
			(layer "F.Fab")
		)
		(fp_line
			(start 0.12065 -0.3048)
			(end 0.67945 -0.3048)
			(stroke
				(width 0.1)
				(type default)
			)
			(layer "F.Fab")
		)
		(fp_line
			(start 0.67945 -0.3048)
			(end 0.67945 0.3048)
			(stroke
				(width 0.1)
				(type default)
			)
			(layer "F.Fab")
		)
		(fp_line
			(start -0.67945 -0.305054)
			(end -0.12065 -0.305054)
			(stroke
				(width 0.1)
				(type default)
			)
			(layer "F.Fab")
		)
		(fp_line
			(start -0.12065 -0.305054)
			(end -0.12065 -0.2794)
			(stroke
				(width 0.1)
				(type default)
			)
			(layer "F.Fab")
		)
		(pad "1" smd circle
			(at -0.40005 0 270)
			(size 0 0)
			(layers "F.Cu" "F.Mask" "F.Paste")
			(net "PGPPA_AUX")
		)
		(pad "2" smd circle
			(at 0.40005 0 270)
			(size 0 0)
			(layers "F.Cu" "F.Mask" "F.Paste")
			(net "GND")
		)
	)
	(footprint ""
		(layer "F.Cu")
		(at 124.66574 -79.649828)
		(property "Reference" "R4630"
			(at 0 0 0)
			(layer "F.SilkS")
			(hide yes)
			(effects
				(font
					(size 1.27 1.27)
				)
			)
		)
		(property "Value" ""
			(at 0 0 0)
			(layer "F.Fab")
			(effects
				(font
					(size 1.27 1.27)
				)
			)
		)
		(duplicate_pad_numbers_are_jumpers no)
		(fp_line
			(start -0.7874 -0.4064)
			(end 0.7874 -0.4064)
			(stroke
				(width 0.1524)
				(type default)
			)
			(layer "F.SilkS")
		)
		(fp_line
			(start -0.7874 0.4064)
			(end -0.7874 -0.4064)
			(stroke
				(width 0.1524)
				(type default)
			)
			(layer "F.SilkS")
		)
		(fp_line
			(start 0.7874 -0.4064)
			(end 0.7874 0.4064)
			(stroke
				(width 0.1524)
				(type default)
			)
			(layer "F.SilkS")
		)
		(fp_line
			(start 0.7874 0.4064)
			(end -0.7874 0.4064)
			(stroke
				(width 0.1524)
				(type default)
			)
			(layer "F.SilkS")
		)
		(fp_line
			(start -0.67945 -0.305054)
			(end -0.12065 -0.305054)
			(stroke
				(width 0.1)
				(type default)
			)
			(layer "F.Fab")
		)
		(fp_line
			(start -0.67945 0.3048)
			(end -0.67945 -0.305054)
			(stroke
				(width 0.1)
				(type default)
			)
			(layer "F.Fab")
		)
		(fp_line
			(start -0.12065 -0.305054)
			(end -0.12065 -0.2794)
			(stroke
				(width 0.1)
				(type default)
			)
			(layer "F.Fab")
		)
		(fp_line
			(start -0.12065 -0.2794)
			(end 0.12065 -0.2794)
			(stroke
				(width 0.1)
				(type default)
			)
			(layer "F.Fab")
		)
		(fp_line
			(start -0.12065 0.2794)
			(end -0.12065 0.3048)
			(stroke
				(width 0.1)
				(type default)
			)
			(layer "F.Fab")
		)
		(fp_line
			(start -0.12065 0.3048)
			(end -0.67945 0.3048)
			(stroke
				(width 0.1)
				(type default)
			)
			(layer "F.Fab")
		)
		(fp_line
			(start 0.120396 0.2794)
			(end -0.12065 0.2794)
			(stroke
				(width 0.1)
				(type default)
			)
			(layer "F.Fab")
		)
		(fp_line
			(start 0.120396 0.3048)
			(end 0.120396 0.2794)
			(stroke
				(width 0.1)
				(type default)
			)
			(layer "F.Fab")
		)
		(fp_line
			(start 0.12065 -0.3048)
			(end 0.67945 -0.3048)
			(stroke
				(width 0.1)
				(type default)
			)
			(layer "F.Fab")
		)
		(fp_line
			(start 0.12065 -0.2794)
			(end 0.12065 -0.3048)
			(stroke
				(width 0.1)
				(type default)
			)
			(layer "F.Fab")
		)
		(fp_line
			(start 0.67945 -0.3048)
			(end 0.67945 0.3048)
			(stroke
				(width 0.1)
				(type default)
			)
			(layer "F.Fab")
		)
		(fp_line
			(start 0.67945 0.3048)
			(end 0.120396 0.3048)
			(stroke
				(width 0.1)
				(type default)
			)
			(layer "F.Fab")
		)
		(pad "1" smd circle
			(at -0.40005 0)
			(size 0 0)
			(layers "F.Cu" "F.Mask" "F.Paste")
			(net "JTAG_BMC_SW_TDO_R")
		)
		(pad "2" smd circle
			(at 0.40005 0)
			(size 0 0)
			(layers "F.Cu" "F.Mask" "F.Paste")
			(net "JTAG_BMC_SW_TDO")
		)
	)
	(footprint ""
		(layer "F.Cu")
		(at 201.02068 -101.145848 180)
		(property "Reference" "R220"
			(at 0 0 180)
			(layer "F.SilkS")
			(hide yes)
			(effects
				(font
					(size 1.27 1.27)
				)
			)
		)
		(property "Value" ""
			(at 0 0 180)
			(layer "F.Fab")
			(effects
				(font
					(size 1.27 1.27)
				)
			)
		)
		(duplicate_pad_numbers_are_jumpers no)
		(fp_line
			(start 0.7874 0.4064)
			(end -0.7874 0.4064)
			(stroke
				(width 0.1524)
				(type default)
			)
			(layer "F.SilkS")
		)
		(fp_line
			(start 0.7874 -0.4064)
			(end 0.7874 0.4064)
			(stroke
				(width 0.1524)
				(type default)
			)
			(layer "F.SilkS")
		)
		(fp_line
			(start -0.7874 0.4064)
			(end -0.7874 -0.4064)
			(stroke
				(width 0.1524)
				(type default)
			)
			(layer "F.SilkS")
		)
		(fp_line
			(start -0.7874 -0.4064)
			(end 0.7874 -0.4064)
			(stroke
				(width 0.1524)
				(type default)
			)
			(layer "F.SilkS")
		)
		(fp_line
			(start 0.67945 0.3048)
			(end 0.120396 0.3048)
			(stroke
				(width 0.1)
				(type default)
			)
			(layer "F.Fab")
		)
		(fp_line
			(start 0.67945 -0.3048)
			(end 0.67945 0.3048)
			(stroke
				(width 0.1)
				(type default)
			)
			(layer "F.Fab")
		)
		(fp_line
			(start 0.12065 -0.2794)
			(end 0.12065 -0.3048)
			(stroke
				(width 0.1)
				(type default)
			)
			(layer "F.Fab")
		)
		(fp_line
			(start 0.12065 -0.3048)
			(end 0.67945 -0.3048)
			(stroke
				(width 0.1)
				(type default)
			)
			(layer "F.Fab")
		)
		(fp_line
			(start 0.120396 0.3048)
			(end 0.120396 0.2794)
			(stroke
				(width 0.1)
				(type default)
			)
			(layer "F.Fab")
		)
		(fp_line
			(start 0.120396 0.2794)
			(end -0.12065 0.2794)
			(stroke
				(width 0.1)
				(type default)
			)
			(layer "F.Fab")
		)
		(fp_line
			(start -0.12065 0.3048)
			(end -0.67945 0.3048)
			(stroke
				(width 0.1)
				(type default)
			)
			(layer "F.Fab")
		)
		(fp_line
			(start -0.12065 0.2794)
			(end -0.12065 0.3048)
			(stroke
				(width 0.1)
				(type default)
			)
			(layer "F.Fab")
		)
		(fp_line
			(start -0.12065 -0.2794)
			(end 0.12065 -0.2794)
			(stroke
				(width 0.1)
				(type default)
			)
			(layer "F.Fab")
		)
		(fp_line
			(start -0.12065 -0.305054)
			(end -0.12065 -0.2794)
			(stroke
				(width 0.1)
				(type default)
			)
			(layer "F.Fab")
		)
		(fp_line
			(start -0.67945 0.3048)
			(end -0.67945 -0.305054)
			(stroke
				(width 0.1)
				(type default)
			)
			(layer "F.Fab")
		)
		(fp_line
			(start -0.67945 -0.305054)
			(end -0.12065 -0.305054)
			(stroke
				(width 0.1)
				(type default)
			)
			(layer "F.Fab")
		)
		(pad "1" smd circle
			(at -0.40005 0 180)
			(size 0 0)
			(layers "F.Cu" "F.Mask" "F.Paste")
			(net "PVNN_TERM_CPU1")
		)
		(pad "2" smd circle
			(at 0.40005 0 180)
			(size 0 0)
			(layers "F.Cu" "F.Mask" "F.Paste")
			(net "H_CPU1_MEMHOT_IN_LVC1_R1_N")
		)
	)
	(footprint ""
		(layer "F.Cu")
		(at 258.10845 -70.40626 -90)
		(property "Reference" "PC1218"
			(at 0 0 270)
			(layer "F.SilkS")
			(hide yes)
			(effects
				(font
					(size 1.27 1.27)
				)
			)
		)
		(property "Value" ""
			(at 0 0 270)
			(layer "F.Fab")
			(effects
				(font
					(size 1.27 1.27)
				)
			)
		)
		(duplicate_pad_numbers_are_jumpers no)
		(fp_line
			(start -1.524 0.762)
			(end -1.524 -0.762)
			(stroke
				(width 0.1524)
				(type default)
			)
			(layer "F.SilkS")
		)
		(fp_line
			(start 1.524 0.762)
			(end -1.524 0.762)
			(stroke
				(width 0.1524)
				(type default)
			)
			(layer "F.SilkS")
		)
		(fp_line
			(start -1.524 -0.762)
			(end 1.524 -0.762)
			(stroke
				(width 0.1524)
				(type default)
			)
			(layer "F.SilkS")
		)
		(fp_line
			(start 1.524 -0.762)
			(end 1.524 0.762)
			(stroke
				(width 0.1524)
				(type default)
			)
			(layer "F.SilkS")
		)
		(fp_line
			(start -1.1049 0.724916)
			(end 1.1049 0.724916)
			(stroke
				(width 0.1)
				(type default)
			)
			(layer "F.Fab")
		)
		(fp_line
			(start 1.1049 0.724916)
			(end 1.1049 -0.724916)
			(stroke
				(width 0.1)
				(type default)
			)
			(layer "F.Fab")
		)
		(fp_line
			(start -1.1049 -0.724916)
			(end -1.1049 0.724916)
			(stroke
				(width 0.1)
				(type default)
			)
			(layer "F.Fab")
		)
		(fp_line
			(start 1.1049 -0.724916)
			(end -1.1049 -0.724916)
			(stroke
				(width 0.1)
				(type default)
			)
			(layer "F.Fab")
		)
		(pad "1" smd rect
			(at -0.889 0 90)
			(size 1.016 1.27)
			(layers "F.Cu" "F.Mask" "F.Paste")
			(net "SW_P12V_AUX_P1V05_PCH_AUX_FLT")
		)
		(pad "2" smd rect
			(at 0.889 0 90)
			(size 1.016 1.27)
			(layers "F.Cu" "F.Mask" "F.Paste")
			(net "GND")
		)
	)
	(footprint ""
		(layer "F.Cu")
		(at 456.621388 -381.264922 -90)
		(property "Reference" "PR89"
			(at 0 0 270)
			(layer "F.SilkS")
			(hide yes)
			(effects
				(font
					(size 1.27 1.27)
				)
			)
		)
		(property "Value" ""
			(at 0 0 270)
			(layer "F.Fab")
			(effects
				(font
					(size 1.27 1.27)
				)
			)
		)
		(duplicate_pad_numbers_are_jumpers no)
		(fp_line
			(start -0.7874 0.4064)
			(end -0.7874 -0.4064)
			(stroke
				(width 0.1524)
				(type default)
			)
			(layer "F.SilkS")
		)
		(fp_line
			(start 0.7874 0.4064)
			(end -0.7874 0.4064)
			(stroke
				(width 0.1524)
				(type default)
			)
			(layer "F.SilkS")
		)
		(fp_line
			(start -0.7874 -0.4064)
			(end 0.7874 -0.4064)
			(stroke
				(width 0.1524)
				(type default)
			)
			(layer "F.SilkS")
		)
		(fp_line
			(start 0.7874 -0.4064)
			(end 0.7874 0.4064)
			(stroke
				(width 0.1524)
				(type default)
			)
			(layer "F.SilkS")
		)
		(fp_line
			(start -0.67945 0.3048)
			(end -0.67945 -0.305054)
			(stroke
				(width 0.1)
				(type default)
			)
			(layer "F.Fab")
		)
		(fp_line
			(start -0.12065 0.3048)
			(end -0.67945 0.3048)
			(stroke
				(width 0.1)
				(type default)
			)
			(layer "F.Fab")
		)
		(fp_line
			(start 0.120396 0.3048)
			(end 0.120396 0.2794)
			(stroke
				(width 0.1)
				(type default)
			)
			(layer "F.Fab")
		)
		(fp_line
			(start 0.67945 0.3048)
			(end 0.120396 0.3048)
			(stroke
				(width 0.1)
				(type default)
			)
			(layer "F.Fab")
		)
		(fp_line
			(start -0.12065 0.2794)
			(end -0.12065 0.3048)
			(stroke
				(width 0.1)
				(type default)
			)
			(layer "F.Fab")
		)
		(fp_line
			(start 0.120396 0.2794)
			(end -0.12065 0.2794)
			(stroke
				(width 0.1)
				(type default)
			)
			(layer "F.Fab")
		)
		(fp_line
			(start -0.12065 -0.2794)
			(end 0.12065 -0.2794)
			(stroke
				(width 0.1)
				(type default)
			)
			(layer "F.Fab")
		)
		(fp_line
			(start 0.12065 -0.2794)
			(end 0.12065 -0.3048)
			(stroke
				(width 0.1)
				(type default)
			)
			(layer "F.Fab")
		)
		(fp_line
			(start 0.12065 -0.3048)
			(end 0.67945 -0.3048)
			(stroke
				(width 0.1)
				(type default)
			)
			(layer "F.Fab")
		)
		(fp_line
			(start 0.67945 -0.3048)
			(end 0.67945 0.3048)
			(stroke
				(width 0.1)
				(type default)
			)
			(layer "F.Fab")
		)
		(fp_line
			(start -0.67945 -0.305054)
			(end -0.12065 -0.305054)
			(stroke
				(width 0.1)
				(type default)
			)
			(layer "F.Fab")
		)
		(fp_line
			(start -0.12065 -0.305054)
			(end -0.12065 -0.2794)
			(stroke
				(width 0.1)
				(type default)
			)
			(layer "F.Fab")
		)
		(pad "1" smd circle
			(at -0.40005 0 270)
			(size 0 0)
			(layers "F.Cu" "F.Mask" "F.Paste")
			(net "P5V_AUX_CS")
		)
		(pad "2" smd circle
			(at 0.40005 0 270)
			(size 0 0)
			(layers "F.Cu" "F.Mask" "F.Paste")
			(net "GND")
		)
	)
)
